(kicad_pcb
	(version 20260206)
	(generator "pcbnew")
	(generator_version "10.0")
	(general
		(thickness 1.6)
		(legacy_teardrops no)
	)
	(paper "A4")
	(title_block
		(title "panther-plus-userver — 13130-1b_20150205.brd")
		(comment 1 "Honey Badger (Wiwynn) / footprint 624 of 1509 (DIMM4), pads 16-22 of 210")
	)
	(layers
		(0 "F.Cu" signal "TOP")
		(4 "In1.Cu" signal "L2")
		(6 "In2.Cu" signal "L3")
		(8 "In3.Cu" signal "L4")
		(10 "In4.Cu" signal "L5")
		(12 "In5.Cu" signal "L6")
		(14 "In6.Cu" signal "L7")
		(16 "In7.Cu" signal "L8")
		(18 "In8.Cu" signal "L9")
		(20 "In9.Cu" signal "L10")
		(22 "In10.Cu" signal "L11")
		(2 "B.Cu" signal "BOTTOM")
		(9 "F.Adhes" user "F.Adhesive")
		(11 "B.Adhes" user "B.Adhesive")
		(13 "F.Paste" user "Package Geometry/Pastemask Top")
		(15 "B.Paste" user "Package Geometry/Pastemask Bottom")
		(5 "F.SilkS" user "Ref Des/Silkscreen Top")
		(7 "B.SilkS" user "Ref Des/Silkscreen Bottom")
		(1 "F.Mask" user "Board Geometry/Soldermask Top")
		(3 "B.Mask" user "Board Geometry/Soldermask Bottom")
		(17 "Dwgs.User" user "User.Drawings")
		(19 "Cmts.User" user "User.Comments")
		(21 "Eco1.User" user "User.Eco1")
		(23 "Eco2.User" user "User.Eco2")
		(25 "Edge.Cuts" user "Board Geometry/Outline")
		(27 "Margin" user)
		(31 "F.CrtYd" user "Package Geometry/Place Bound Top")
		(29 "B.CrtYd" user "Package Geometry/Place Bound Bottom")
		(35 "F.Fab" user "Ref Des/Assembly Top")
		(33 "B.Fab" user "Ref Des/Assembly Bottom")
	)
	(footprint ""
		(layer "F.Cu")
		(at 159.999934 -5.790692)
		(property "Reference" "DIMM4"
			(at 0 0 0)
			(layer "F.SilkS")
			(hide yes)
			(effects
				(font
					(size 1.27 1.27)
				)
			)
		)
		(property "Value" "DDR3-204P-174-COLAY-1-GP"
			(at -40.682164 -17.468088 0)
			(unlocked yes)
			(layer "F.Fab")
			(hide yes)
			(effects
				(font
					(size 1.016 1.016)
					(thickness 0.1524)
				)
			)
		)
		(property "Device Type" "AS0A626-H8SN-7H-COLAY-1"
			(at -40.682164 -18.992088 0)
			(unlocked yes)
			(layer "F.Fab")
			(hide yes)
			(effects
				(font
					(size 1.016 1.016)
					(thickness 0.1524)
				)
			)
		)
		(duplicate_pad_numbers_are_jumpers no)
		(pad "14" smd custom
			(at -27.750008 -4.106672)
			(size 0.1143 0.1143)
			(layers "F.Cu" "F.Mask" "F.Paste")
			(net "GND")
			(options
				(clearance outline)
				(anchor circle)
			)
			(primitives
				(gr_poly
					(pts
						(xy 0 0.9017) (xy -0.03175 0.89916) (xy -0.0635 0.889) (xy -0.09144 0.87376) (xy -0.11684 0.85344)
						(xy -0.13716 0.82804) (xy -0.1524 0.8001) (xy -0.16256 0.76835) (xy -0.1651 0.7366) (xy -0.1651 0.44958)
						(xy -0.17272 0.44196) (xy -0.19812 0.4064) (xy -0.2032 0.39624) (xy -0.20701 0.38735) (xy -0.21209 0.37719)
						(xy -0.2159 0.36703) (xy -0.21844 0.35687) (xy -0.22225 0.34544) (xy -0.22352 0.33528) (xy -0.22606 0.32512)
						(xy -0.22733 0.31369) (xy -0.22733 0.30353) (xy -0.2286 0.2921) (xy -0.22733 0.28067) (xy -0.22733 0.27051)
						(xy -0.22606 0.25908) (xy -0.22352 0.24892) (xy -0.22225 0.23876) (xy -0.21844 0.22733) (xy -0.2159 0.21717)
						(xy -0.21209 0.20701) (xy -0.20701 0.19685) (xy -0.2032 0.18796) (xy -0.19812 0.1778) (xy -0.17272 0.14224)
						(xy -0.1651 0.13462) (xy -0.1651 -0.7366) (xy -0.16256 -0.76835) (xy -0.1524 -0.8001) (xy -0.13716 -0.82804)
						(xy -0.11684 -0.85344) (xy -0.09144 -0.87376) (xy -0.0635 -0.889) (xy -0.03175 -0.89916) (xy 0 -0.9017)
						(xy 0.03175 -0.89916) (xy 0.0635 -0.889) (xy 0.09144 -0.87376) (xy 0.11684 -0.85344) (xy 0.13716 -0.82804)
						(xy 0.1524 -0.8001) (xy 0.16256 -0.76835) (xy 0.1651 -0.7366) (xy 0.1651 0.13462) (xy 0.17272 0.14224)
						(xy 0.19812 0.1778) (xy 0.2032 0.18796) (xy 0.20701 0.19685) (xy 0.21209 0.20701) (xy 0.2159 0.21717)
						(xy 0.21844 0.22733) (xy 0.22225 0.23876) (xy 0.22352 0.24892) (xy 0.22606 0.25908) (xy 0.22733 0.27051)
						(xy 0.22733 0.28067) (xy 0.2286 0.2921) (xy 0.22733 0.30353) (xy 0.22733 0.31369) (xy 0.22606 0.32512)
						(xy 0.22352 0.33528) (xy 0.22225 0.34544) (xy 0.21844 0.35687) (xy 0.2159 0.36703) (xy 0.21209 0.37719)
						(xy 0.20701 0.38735) (xy 0.2032 0.39624) (xy 0.19812 0.4064) (xy 0.17272 0.44196) (xy 0.1651 0.44958)
						(xy 0.1651 0.7366) (xy 0.16256 0.76835) (xy 0.1524 0.8001) (xy 0.13716 0.82804) (xy 0.11684 0.85344)
						(xy 0.09144 0.87376) (xy 0.0635 0.889) (xy 0.03175 0.89916)
					)
					(width 0)
					(fill yes)
				)
			)
		)
		(pad "15" smd custom
			(at -27.450034 4.106672)
			(size 0.1143 0.1143)
			(layers "F.Cu" "F.Mask" "F.Paste")
			(net "M_B_DQ7")
			(options
				(clearance outline)
				(anchor circle)
			)
			(primitives
				(gr_poly
					(pts
						(xy 0 0.9017) (xy -0.03175 0.89916) (xy -0.0635 0.889) (xy -0.09144 0.87376) (xy -0.11684 0.85344)
						(xy -0.13716 0.82804) (xy -0.1524 0.8001) (xy -0.16256 0.76835) (xy -0.1651 0.7366) (xy -0.1651 0.11938)
						(xy -0.17272 0.11176) (xy -0.19812 0.0762) (xy -0.2032 0.06604) (xy -0.20701 0.05715) (xy -0.21209 0.04699)
						(xy -0.2159 0.03683) (xy -0.21844 0.02667) (xy -0.22225 0.01524) (xy -0.22352 0.00508) (xy -0.22606 -0.00508)
						(xy -0.22733 -0.01651) (xy -0.22733 -0.02667) (xy -0.2286 -0.0381) (xy -0.22733 -0.04953) (xy -0.22733 -0.05969)
						(xy -0.22606 -0.07112) (xy -0.22352 -0.08128) (xy -0.22225 -0.09144) (xy -0.21844 -0.10287) (xy -0.2159 -0.11303)
						(xy -0.21209 -0.12319) (xy -0.20701 -0.13335) (xy -0.2032 -0.14224) (xy -0.19812 -0.1524) (xy -0.17272 -0.18796)
						(xy -0.1651 -0.19558) (xy -0.1651 -0.7366) (xy -0.16256 -0.76835) (xy -0.1524 -0.8001) (xy -0.13716 -0.82804)
						(xy -0.11684 -0.85344) (xy -0.09144 -0.87376) (xy -0.0635 -0.889) (xy -0.03175 -0.89916) (xy 0 -0.9017)
						(xy 0.03175 -0.89916) (xy 0.0635 -0.889) (xy 0.09144 -0.87376) (xy 0.11684 -0.85344) (xy 0.13716 -0.82804)
						(xy 0.1524 -0.8001) (xy 0.16256 -0.76835) (xy 0.1651 -0.7366) (xy 0.1651 -0.19685) (xy 0.17272 -0.18923)
						(xy 0.17907 -0.18034) (xy 0.18669 -0.17145) (xy 0.19177 -0.16256) (xy 0.19812 -0.15367) (xy 0.20828 -0.13335)
						(xy 0.21971 -0.10287) (xy 0.22225 -0.09271) (xy 0.22479 -0.08128) (xy 0.22606 -0.07112) (xy 0.2286 -0.05969)
						(xy 0.2286 -0.01651) (xy 0.22606 -0.00508) (xy 0.22479 0.00508) (xy 0.22225 0.01651) (xy 0.21971 0.02667)
						(xy 0.20828 0.05715) (xy 0.19812 0.07747) (xy 0.19177 0.08636) (xy 0.18669 0.09525) (xy 0.17907 0.10414)
						(xy 0.17272 0.11303) (xy 0.1651 0.12065) (xy 0.1651 0.7366) (xy 0.16256 0.76835) (xy 0.1524 0.8001)
						(xy 0.13716 0.82804) (xy 0.11684 0.85344) (xy 0.09144 0.87376) (xy 0.0635 0.889) (xy 0.03175 0.89916)
					)
					(width 0)
					(fill yes)
				)
			)
		)
		(pad "16" smd custom
			(at -27.15006 -4.106672)
			(size 0.1143 0.1143)
			(layers "F.Cu" "F.Mask" "F.Paste")
			(net "M_B_DQ2")
			(options
				(clearance outline)
				(anchor circle)
			)
			(primitives
				(gr_poly
					(pts
						(xy 0 0.9017) (xy -0.03175 0.89916) (xy -0.0635 0.889) (xy -0.09144 0.87376) (xy -0.11684 0.85344)
						(xy -0.13716 0.82804) (xy -0.1524 0.8001) (xy -0.16256 0.76835) (xy -0.1651 0.7366) (xy -0.1651 0.19685)
						(xy -0.17272 0.18923) (xy -0.17907 0.18034) (xy -0.18669 0.17145) (xy -0.19177 0.16256) (xy -0.19812 0.15367)
						(xy -0.20828 0.13335) (xy -0.21971 0.10287) (xy -0.22225 0.09271) (xy -0.22479 0.08128) (xy -0.22606 0.07112)
						(xy -0.2286 0.05969) (xy -0.2286 0.01651) (xy -0.22606 0.00508) (xy -0.22479 -0.00508) (xy -0.22225 -0.01651)
						(xy -0.21971 -0.02667) (xy -0.20828 -0.05715) (xy -0.19812 -0.07747) (xy -0.19177 -0.08636) (xy -0.18669 -0.09525)
						(xy -0.17907 -0.10414) (xy -0.17272 -0.11303) (xy -0.1651 -0.12065) (xy -0.1651 -0.7366) (xy -0.16256 -0.76835)
						(xy -0.1524 -0.8001) (xy -0.13716 -0.82804) (xy -0.11684 -0.85344) (xy -0.09144 -0.87376) (xy -0.0635 -0.889)
						(xy -0.03175 -0.89916) (xy 0 -0.9017) (xy 0.03175 -0.89916) (xy 0.0635 -0.889) (xy 0.09144 -0.87376)
						(xy 0.11684 -0.85344) (xy 0.13716 -0.82804) (xy 0.1524 -0.8001) (xy 0.16256 -0.76835) (xy 0.1651 -0.7366)
						(xy 0.1651 -0.11938) (xy 0.17272 -0.11176) (xy 0.19812 -0.0762) (xy 0.2032 -0.06604) (xy 0.20701 -0.05715)
						(xy 0.21209 -0.04699) (xy 0.2159 -0.03683) (xy 0.21844 -0.02667) (xy 0.22225 -0.01524) (xy 0.22352 -0.00508)
						(xy 0.22606 0.00508) (xy 0.22733 0.01651) (xy 0.22733 0.02667) (xy 0.2286 0.0381) (xy 0.22733 0.04953)
						(xy 0.22733 0.05969) (xy 0.22606 0.07112) (xy 0.22352 0.08128) (xy 0.22225 0.09144) (xy 0.21844 0.10287)
						(xy 0.2159 0.11303) (xy 0.21209 0.12319) (xy 0.20701 0.13335) (xy 0.2032 0.14224) (xy 0.19812 0.1524)
						(xy 0.17272 0.18796) (xy 0.1651 0.19558) (xy 0.1651 0.7366) (xy 0.16256 0.76835) (xy 0.1524 0.8001)
						(xy 0.13716 0.82804) (xy 0.11684 0.85344) (xy 0.09144 0.87376) (xy 0.0635 0.889) (xy 0.03175 0.89916)
					)
					(width 0)
					(fill yes)
				)
			)
		)
		(pad "17" smd custom
			(at -26.850086 4.106672)
			(size 0.1143 0.1143)
			(layers "F.Cu" "F.Mask" "F.Paste")
			(net "GND")
			(options
				(clearance outline)
				(anchor circle)
			)
			(primitives
				(gr_poly
					(pts
						(xy 0 0.9017) (xy -0.03175 0.89916) (xy -0.0635 0.889) (xy -0.09144 0.87376) (xy -0.11684 0.85344)
						(xy -0.13716 0.82804) (xy -0.1524 0.8001) (xy -0.16256 0.76835) (xy -0.1651 0.7366) (xy -0.1651 -0.13462)
						(xy -0.17272 -0.14224) (xy -0.19812 -0.1778) (xy -0.2032 -0.18796) (xy -0.20701 -0.19685) (xy -0.21209 -0.20701)
						(xy -0.2159 -0.21717) (xy -0.21844 -0.22733) (xy -0.22225 -0.23876) (xy -0.22352 -0.24892) (xy -0.22606 -0.25908)
						(xy -0.22733 -0.27051) (xy -0.22733 -0.28067) (xy -0.2286 -0.2921) (xy -0.22733 -0.30353) (xy -0.22733 -0.31369)
						(xy -0.22606 -0.32512) (xy -0.22352 -0.33528) (xy -0.22225 -0.34544) (xy -0.21844 -0.35687) (xy -0.2159 -0.36703)
						(xy -0.21209 -0.37719) (xy -0.20701 -0.38735) (xy -0.2032 -0.39624) (xy -0.19812 -0.4064) (xy -0.17272 -0.44196)
						(xy -0.1651 -0.44958) (xy -0.1651 -0.7366) (xy -0.16256 -0.76835) (xy -0.1524 -0.8001) (xy -0.13716 -0.82804)
						(xy -0.11684 -0.85344) (xy -0.09144 -0.87376) (xy -0.0635 -0.889) (xy -0.03175 -0.89916) (xy 0 -0.9017)
						(xy 0.03175 -0.89916) (xy 0.0635 -0.889) (xy 0.09144 -0.87376) (xy 0.11684 -0.85344) (xy 0.13716 -0.82804)
						(xy 0.1524 -0.8001) (xy 0.16256 -0.76835) (xy 0.1651 -0.7366) (xy 0.1651 -0.44958) (xy 0.17272 -0.44196)
						(xy 0.19812 -0.4064) (xy 0.2032 -0.39624) (xy 0.20701 -0.38735) (xy 0.21209 -0.37719) (xy 0.2159 -0.36703)
						(xy 0.21844 -0.35687) (xy 0.22225 -0.34544) (xy 0.22352 -0.33528) (xy 0.22606 -0.32512) (xy 0.22733 -0.31369)
						(xy 0.22733 -0.30353) (xy 0.2286 -0.2921) (xy 0.22733 -0.28067) (xy 0.22733 -0.27051) (xy 0.22606 -0.25908)
						(xy 0.22352 -0.24892) (xy 0.22225 -0.23876) (xy 0.21844 -0.22733) (xy 0.2159 -0.21717) (xy 0.21209 -0.20701)
						(xy 0.20701 -0.19685) (xy 0.2032 -0.18796) (xy 0.19812 -0.1778) (xy 0.17272 -0.14224) (xy 0.1651 -0.13462)
						(xy 0.1651 0.7366) (xy 0.16256 0.76835) (xy 0.1524 0.8001) (xy 0.13716 0.82804) (xy 0.11684 0.85344)
						(xy 0.09144 0.87376) (xy 0.0635 0.889) (xy 0.03175 0.89916)
					)
					(width 0)
					(fill yes)
				)
			)
		)
		(pad "18" smd custom
			(at -26.550112 -4.106672)
			(size 0.1143 0.1143)
			(layers "F.Cu" "F.Mask" "F.Paste")
			(net "M_B_DQ3")
			(options
				(clearance outline)
				(anchor circle)
			)
			(primitives
				(gr_poly
					(pts
						(xy 0 0.9017) (xy -0.03175 0.89916) (xy -0.0635 0.889) (xy -0.09144 0.87376) (xy -0.11684 0.85344)
						(xy -0.13716 0.82804) (xy -0.1524 0.8001) (xy -0.16256 0.76835) (xy -0.1651 0.7366) (xy -0.1651 0.44958)
						(xy -0.17272 0.44196) (xy -0.19812 0.4064) (xy -0.2032 0.39624) (xy -0.20701 0.38735) (xy -0.21209 0.37719)
						(xy -0.2159 0.36703) (xy -0.21844 0.35687) (xy -0.22225 0.34544) (xy -0.22352 0.33528) (xy -0.22606 0.32512)
						(xy -0.22733 0.31369) (xy -0.22733 0.30353) (xy -0.2286 0.2921) (xy -0.22733 0.28067) (xy -0.22733 0.27051)
						(xy -0.22606 0.25908) (xy -0.22352 0.24892) (xy -0.22225 0.23876) (xy -0.21844 0.22733) (xy -0.2159 0.21717)
						(xy -0.21209 0.20701) (xy -0.20701 0.19685) (xy -0.2032 0.18796) (xy -0.19812 0.1778) (xy -0.17272 0.14224)
						(xy -0.1651 0.13462) (xy -0.1651 -0.7366) (xy -0.16256 -0.76835) (xy -0.1524 -0.8001) (xy -0.13716 -0.82804)
						(xy -0.11684 -0.85344) (xy -0.09144 -0.87376) (xy -0.0635 -0.889) (xy -0.03175 -0.89916) (xy 0 -0.9017)
						(xy 0.03175 -0.89916) (xy 0.0635 -0.889) (xy 0.09144 -0.87376) (xy 0.11684 -0.85344) (xy 0.13716 -0.82804)
						(xy 0.1524 -0.8001) (xy 0.16256 -0.76835) (xy 0.1651 -0.7366) (xy 0.1651 0.13462) (xy 0.17272 0.14224)
						(xy 0.19812 0.1778) (xy 0.2032 0.18796) (xy 0.20701 0.19685) (xy 0.21209 0.20701) (xy 0.2159 0.21717)
						(xy 0.21844 0.22733) (xy 0.22225 0.23876) (xy 0.22352 0.24892) (xy 0.22606 0.25908) (xy 0.22733 0.27051)
						(xy 0.22733 0.28067) (xy 0.2286 0.2921) (xy 0.22733 0.30353) (xy 0.22733 0.31369) (xy 0.22606 0.32512)
						(xy 0.22352 0.33528) (xy 0.22225 0.34544) (xy 0.21844 0.35687) (xy 0.2159 0.36703) (xy 0.21209 0.37719)
						(xy 0.20701 0.38735) (xy 0.2032 0.39624) (xy 0.19812 0.4064) (xy 0.17272 0.44196) (xy 0.1651 0.44958)
						(xy 0.1651 0.7366) (xy 0.16256 0.76835) (xy 0.1524 0.8001) (xy 0.13716 0.82804) (xy 0.11684 0.85344)
						(xy 0.09144 0.87376) (xy 0.0635 0.889) (xy 0.03175 0.89916)
					)
					(width 0)
					(fill yes)
				)
			)
		)
		(pad "19" smd custom
			(at -26.249884 4.106672)
			(size 0.1143 0.1143)
			(layers "F.Cu" "F.Mask" "F.Paste")
			(net "M_B_DQ12")
			(options
				(clearance outline)
				(anchor circle)
			)
			(primitives
				(gr_poly
					(pts
						(xy 0 0.9017) (xy -0.03175 0.89916) (xy -0.0635 0.889) (xy -0.09144 0.87376) (xy -0.11684 0.85344)
						(xy -0.13716 0.82804) (xy -0.1524 0.8001) (xy -0.16256 0.76835) (xy -0.1651 0.7366) (xy -0.1651 0.11938)
						(xy -0.17272 0.11176) (xy -0.19812 0.0762) (xy -0.2032 0.06604) (xy -0.20701 0.05715) (xy -0.21209 0.04699)
						(xy -0.2159 0.03683) (xy -0.21844 0.02667) (xy -0.22225 0.01524) (xy -0.22352 0.00508) (xy -0.22606 -0.00508)
						(xy -0.22733 -0.01651) (xy -0.22733 -0.02667) (xy -0.2286 -0.0381) (xy -0.22733 -0.04953) (xy -0.22733 -0.05969)
						(xy -0.22606 -0.07112) (xy -0.22352 -0.08128) (xy -0.22225 -0.09144) (xy -0.21844 -0.10287) (xy -0.2159 -0.11303)
						(xy -0.21209 -0.12319) (xy -0.20701 -0.13335) (xy -0.2032 -0.14224) (xy -0.19812 -0.1524) (xy -0.17272 -0.18796)
						(xy -0.1651 -0.19558) (xy -0.1651 -0.7366) (xy -0.16256 -0.76835) (xy -0.1524 -0.8001) (xy -0.13716 -0.82804)
						(xy -0.11684 -0.85344) (xy -0.09144 -0.87376) (xy -0.0635 -0.889) (xy -0.03175 -0.89916) (xy 0 -0.9017)
						(xy 0.03175 -0.89916) (xy 0.0635 -0.889) (xy 0.09144 -0.87376) (xy 0.11684 -0.85344) (xy 0.13716 -0.82804)
						(xy 0.1524 -0.8001) (xy 0.16256 -0.76835) (xy 0.1651 -0.7366) (xy 0.1651 -0.19685) (xy 0.17272 -0.18923)
						(xy 0.17907 -0.18034) (xy 0.18669 -0.17145) (xy 0.19177 -0.16256) (xy 0.19812 -0.15367) (xy 0.20828 -0.13335)
						(xy 0.21971 -0.10287) (xy 0.22225 -0.09271) (xy 0.22479 -0.08128) (xy 0.22606 -0.07112) (xy 0.2286 -0.05969)
						(xy 0.2286 -0.01651) (xy 0.22606 -0.00508) (xy 0.22479 0.00508) (xy 0.22225 0.01651) (xy 0.21971 0.02667)
						(xy 0.20828 0.05715) (xy 0.19812 0.07747) (xy 0.19177 0.08636) (xy 0.18669 0.09525) (xy 0.17907 0.10414)
						(xy 0.17272 0.11303) (xy 0.1651 0.12065) (xy 0.1651 0.7366) (xy 0.16256 0.76835) (xy 0.1524 0.8001)
						(xy 0.13716 0.82804) (xy 0.11684 0.85344) (xy 0.09144 0.87376) (xy 0.0635 0.889) (xy 0.03175 0.89916)
					)
					(width 0)
					(fill yes)
				)
			)
		)
		(pad "20" smd custom
			(at -25.94991 -4.106672)
			(size 0.1143 0.1143)
			(layers "F.Cu" "F.Mask" "F.Paste")
			(net "GND")
			(options
				(clearance outline)
				(anchor circle)
			)
			(primitives
				(gr_poly
					(pts
						(xy 0 0.9017) (xy -0.03175 0.89916) (xy -0.0635 0.889) (xy -0.09144 0.87376) (xy -0.11684 0.85344)
						(xy -0.13716 0.82804) (xy -0.1524 0.8001) (xy -0.16256 0.76835) (xy -0.1651 0.7366) (xy -0.1651 0.19685)
						(xy -0.17272 0.18923) (xy -0.17907 0.18034) (xy -0.18669 0.17145) (xy -0.19177 0.16256) (xy -0.19812 0.15367)
						(xy -0.20828 0.13335) (xy -0.21971 0.10287) (xy -0.22225 0.09271) (xy -0.22479 0.08128) (xy -0.22606 0.07112)
						(xy -0.2286 0.05969) (xy -0.2286 0.01651) (xy -0.22606 0.00508) (xy -0.22479 -0.00508) (xy -0.22225 -0.01651)
						(xy -0.21971 -0.02667) (xy -0.20828 -0.05715) (xy -0.19812 -0.07747) (xy -0.19177 -0.08636) (xy -0.18669 -0.09525)
						(xy -0.17907 -0.10414) (xy -0.17272 -0.11303) (xy -0.1651 -0.12065) (xy -0.1651 -0.7366) (xy -0.16256 -0.76835)
						(xy -0.1524 -0.8001) (xy -0.13716 -0.82804) (xy -0.11684 -0.85344) (xy -0.09144 -0.87376) (xy -0.0635 -0.889)
						(xy -0.03175 -0.89916) (xy 0 -0.9017) (xy 0.03175 -0.89916) (xy 0.0635 -0.889) (xy 0.09144 -0.87376)
						(xy 0.11684 -0.85344) (xy 0.13716 -0.82804) (xy 0.1524 -0.8001) (xy 0.16256 -0.76835) (xy 0.1651 -0.7366)
						(xy 0.1651 -0.11938) (xy 0.17272 -0.11176) (xy 0.19812 -0.0762) (xy 0.2032 -0.06604) (xy 0.20701 -0.05715)
						(xy 0.21209 -0.04699) (xy 0.2159 -0.03683) (xy 0.21844 -0.02667) (xy 0.22225 -0.01524) (xy 0.22352 -0.00508)
						(xy 0.22606 0.00508) (xy 0.22733 0.01651) (xy 0.22733 0.02667) (xy 0.2286 0.0381) (xy 0.22733 0.04953)
						(xy 0.22733 0.05969) (xy 0.22606 0.07112) (xy 0.22352 0.08128) (xy 0.22225 0.09144) (xy 0.21844 0.10287)
						(xy 0.2159 0.11303) (xy 0.21209 0.12319) (xy 0.20701 0.13335) (xy 0.2032 0.14224) (xy 0.19812 0.1524)
						(xy 0.17272 0.18796) (xy 0.1651 0.19558) (xy 0.1651 0.7366) (xy 0.16256 0.76835) (xy 0.1524 0.8001)
						(xy 0.13716 0.82804) (xy 0.11684 0.85344) (xy 0.09144 0.87376) (xy 0.0635 0.889) (xy 0.03175 0.89916)
					)
					(width 0)
					(fill yes)
				)
			)
		)
	)
)
